# BASEBOARD_FAB2 (Tioga Pass) — schematic netlist excerpt (pin names and nets, part order shuffled) for the footprints in the layout excerpt that follows; sources: Cadence DE-HDL packaged netlist, KiCad conversion of Wiwynn_Tioga_Pass_MB.brd

J4G1  SCONN288_H44441004  SCONN  pkg PIP  page 43
  \12v\(1)  = P12V_NVDIMM_ABC
  VSS(93)  = GND
  DQ(4)  = M_A_DQ<5>
  VSS(92)  = GND
  DQ(0)  = M_A_DQ<1>
  VSS(91)  = GND
  DQS9P  = M_A_DQS_DP<9>
  DQS9N  = M_A_DQS_DN<9>
  VSS(90)  = GND
  DQ(6)  = M_A_DQ<7>
  VSS(89)  = GND
  DQ(2)  = M_A_DQ<3>
  VSS(88)  = GND
  DQ(12)  = M_A_DQ<13>
  VSS(87)  = GND
  DQ(8)  = M_A_DQ<9>
  VSS(86)  = GND
  DQS10P  = M_A_DQS_DP<10>
  DQS10N  = M_A_DQS_DN<10>
  VSS(85)  = GND
  DQ(14)  = M_A_DQ<15>
  VSS(84)  = GND
  DQ(10)  = M_A_DQ<11>
  VSS(83)  = GND
  DQ(20)  = M_A_DQ<21>
  VSS(82)  = GND
  DQ(16)  = M_A_DQ<17>
  VSS(81)  = GND
  DQS11P  = M_A_DQS_DP<11>
  DQS11N  = M_A_DQS_DN<11>
  VSS(80)  = GND
  DQ(22)  = M_A_DQ<23>
  VSS(79)  = GND
  DQ(18)  = M_A_DQ<19>
  VSS(78)  = GND
  DQ(28)  = M_A_DQ<29>
  VSS(77)  = GND
  DQ(24)  = M_A_DQ<25>
  VSS(76)  = GND
  DQS12P  = M_A_DQS_DP<12>
  DQS12N  = M_A_DQS_DN<12>
  VSS(75)  = GND
  DQ(30)  = M_A_DQ<31>
  VSS(74)  = GND
  DQ(26)  = M_A_DQ<27>
  VSS(73)  = GND
  CB(4)  = M_A_ECC<5>
  VSS(72)  = GND
  CB(0)  = M_A_ECC<1>
  VSS(71)  = GND
  DQS17P  = M_A_DQS_DP<17>
  DQS17N  = M_A_DQS_DN<17>
  VSS(70)  = GND
  CB(6)  = M_A_ECC<7>
  VSS(69)  = GND
  CB(2)  = M_A_ECC<3>
  VSS(68)  = GND
  RESET_N  = M_ABC_RST_N
  VDD(25)  = PVDDQ_ABC
  CKE(0)  = M_A_CKE<0>
  VDD(24)  = PVDDQ_ABC
  ACT_N  = M_A_ACT_N
  BG(0)  = M_A_BG<0>
  VDD(23)  = PVDDQ_ABC
  A12  = M_A_MA<12>
  A9  = M_A_MA<9>
  VDD(22)  = PVDDQ_ABC
  A8  = M_A_MA<8>
  A6  = M_A_MA<6>
  VDD(21)  = PVDDQ_ABC
  A3  = M_A_MA<3>
  A1  = M_A_MA<1>
  VDD(20)  = PVDDQ_ABC
  CK0P  = M_A_CLK_DP<0>
  CK0N  = M_A_CLK_DN<0>
  VDD(19)  = PVDDQ_ABC
  VTT(1)  = PVTT_ABC
  EVENT_N  = FM_DIMM_EVENT_COD_N
  A0  = M_A_MA<0>
  VDD(18)  = PVDDQ_ABC
  BA(0)  = M_A_BA<0>
  A16_RAS_N  = M_A_MA<16>
  VDD(17)  = PVDDQ_ABC
  S0_N  = M_A_CS_N<0>
  VDD(16)  = PVDDQ_ABC
  A15_CAS_N  = M_A_MA<15>
  ODT(0)  = M_A_ODT<0>
  VDD(15)  = PVDDQ_ABC
  S1_N  = M_A_CS_N<1>
  VDD(14)  = PVDDQ_ABC
  ODT(1)  = M_A_ODT<1>
  VDD(13)  = PVDDQ_ABC
  S2_N_C(0)  = M_A_CS_N<2>
  VSS(67)  = GND
  DQ(36)  = M_A_DQ<37>
  VSS(66)  = GND
  DQ(32)  = M_A_DQ<33>
  VSS(65)  = GND
  DQS13P  = M_A_DQS_DP<13>
  DQS13N  = M_A_DQS_DN<13>
  VSS(64)  = GND
  DQ(38)  = M_A_DQ<39>
  VSS(63)  = GND
  DQ(34)  = M_A_DQ<35>
  VSS(62)  = GND
  DQ(44)  = M_A_DQ<45>
  VSS(61)  = GND
  DQ(40)  = M_A_DQ<41>
  VSS(60)  = GND
  DQS14P  = M_A_DQS_DP<14>
  DQS14N  = M_A_DQS_DN<14>
  VSS(59)  = GND
  DQ(46)  = M_A_DQ<47>
  VSS(58)  = GND
  DQ(42)  = M_A_DQ<43>
  VSS(57)  = GND
  DQ(52)  = M_A_DQ<53>
  VSS(56)  = GND
  DQ(48)  = M_A_DQ<49>
  VSS(55)  = GND
  DQS15P  = M_A_DQS_DP<15>
  DQS15N  = M_A_DQS_DN<15>
  VSS(54)  = GND
  DQ(54)  = M_A_DQ<55>
  VSS(53)  = GND
  DQ(50)  = M_A_DQ<51>
  VSS(52)  = GND
  DQ(60)  = M_A_DQ<61>
  VSS(51)  = GND
  DQ(56)  = M_A_DQ<57>
  VSS(50)  = GND
  DQS16P  = M_A_DQS_DP<16>
  DQS16N  = M_A_DQS_DN<16>
  VSS(49)  = GND
  DQ(62)  = M_A_DQ<63>
  VSS(48)  = GND
  DQ(58)  = M_A_DQ<59>
  VSS(47)  = GND
  SA(0)  = GND
  SA(1)  = GND
  SCL  = SMB_DDR_ABC_VPP_SCL
  VPP(4)  = PVPP_ABC
  VPP(3)  = PVPP_ABC
  RFU(2)  = TP_CH_A_DIMM_A0_RFU_2
  \12v\(0)  = P12V_NVDIMM_ABC
  VREFCA  = M_A_VREF
  VSS(46)  = GND
  DQ(5)  = M_A_DQ<4>
  VSS(45)  = GND
  DQ(1)  = M_A_DQ<0>
  VSS(44)  = GND
  DQS0N  = M_A_DQS_DN<0>
  DQS0P  = M_A_DQS_DP<0>
  VSS(43)  = GND
  DQ(7)  = M_A_DQ<6>
  VSS(42)  = GND
  DQ(3)  = M_A_DQ<2>
  VSS(41)  = GND
  DQ(13)  = M_A_DQ<12>
  VSS(40)  = GND
  DQ(9)  = M_A_DQ<8>
  VSS(39)  = GND
  DQS1N  = M_A_DQS_DN<1>
  DQS1P  = M_A_DQS_DP<1>
  VSS(38)  = GND
  DQ(15)  = M_A_DQ<14>
  VSS(37)  = GND
  DQ(11)  = M_A_DQ<10>
  VSS(36)  = GND
  DQ(21)  = M_A_DQ<20>
  VSS(35)  = GND
  DQ(17)  = M_A_DQ<16>
  VSS(34)  = GND
  DQS2N  = M_A_DQS_DN<2>
  DQS2P  = M_A_DQS_DP<2>
  VSS(33)  = GND
  DQ(23)  = M_A_DQ<22>
  VSS(32)  = GND
  DQ(19)  = M_A_DQ<18>
  VSS(31)  = GND
  DQ(29)  = M_A_DQ<28>
  VSS(30)  = GND
  DQ(25)  = M_A_DQ<24>
  VSS(29)  = GND
  DQS3N  = M_A_DQS_DN<3>
  DQS3P  = M_A_DQS_DP<3>
  VSS(28)  = GND
  DQ(31)  = M_A_DQ<30>
  VSS(27)  = GND
  DQ(27)  = M_A_DQ<26>
  VSS(26)  = GND
  CB(5)  = M_A_ECC<4>
  VSS(25)  = GND
  CB(1)  = M_A_ECC<0>
  VSS(24)  = GND
  DQS8N  = M_A_DQS_DN<8>
  DQS8P  = M_A_DQS_DP<8>
  VSS(23)  = GND
  CB(7)  = M_A_ECC<6>
  VSS(22)  = GND
  CB(3)  = M_A_ECC<2>
  VSS(21)  = GND
  CKE(1)  = M_A_CKE<1>
  VDD(12)  = PVDDQ_ABC
  RFU(0)  = TP_CH_A_DIMM_A0_RFU_0
  VDD(11)  = PVDDQ_ABC
  BG(1)  = M_A_BG<1>
  ALERT_N  = M_A_ALERT_N
  VDD(10)  = PVDDQ_ABC
  A11  = M_A_MA<11>
  A7  = M_A_MA<7>
  VDD(9)  = PVDDQ_ABC
  A5  = M_A_MA<5>
  A4  = M_A_MA<4>
  VDD(8)  = PVDDQ_ABC
  A2  = M_A_MA<2>
  VDD(7)  = PVDDQ_ABC
  CK1P  = M_A_CLK_DP<1>
  CK1N  = M_A_CLK_DN<1>
  VDD(6)  = PVDDQ_ABC
  VTT(0)  = PVTT_ABC
  PAR  = M_A_PAR
  VDD(5)  = PVDDQ_ABC
  BA(1)  = M_A_BA<1>
  A10  = M_A_MA<10>
  VDD(4)  = PVDDQ_ABC
  RFU(1)  = TP_CH_A_DIMM_A0_RFU_1
  A14_WE_N  = M_A_MA<14>
  VDD(3)  = PVDDQ_ABC
  SAVE_N_NC  = FM_ADR_COMPLETE_ABC_N
  VDD(2)  = PVDDQ_ABC
  A13  = M_A_MA<13>
  VDD(1)  = PVDDQ_ABC
  A17  = M_A_MA<17>
  C(2)  = M_A_C<2>
  VDD(0)  = PVDDQ_ABC
  S3_N_C(1)  = M_A_CS_N<3>
  SA(2)  = GND
  VSS(20)  = GND
  DQ(37)  = M_A_DQ<36>
  VSS(19)  = GND
  DQ(33)  = M_A_DQ<32>
  VSS(18)  = GND
  DQS4N  = M_A_DQS_DN<4>
  DQS4P  = M_A_DQS_DP<4>
  VSS(17)  = GND
  DQ(39)  = M_A_DQ<38>
  VSS(16)  = GND
  DQ(35)  = M_A_DQ<34>
  VSS(15)  = GND
  DQ(45)  = M_A_DQ<44>
  VSS(14)  = GND
  DQ(41)  = M_A_DQ<40>
  VSS(13)  = GND
  DQS5N  = M_A_DQS_DN<5>
  DQS5P  = M_A_DQS_DP<5>
  VSS(12)  = GND
  DQ(47)  = M_A_DQ<46>
  VSS(11)  = GND
  DQ(43)  = M_A_DQ<42>
  VSS(10)  = GND
  DQ(53)  = M_A_DQ<52>
  VSS(9)  = GND
  DQ(49)  = M_A_DQ<48>
  VSS(8)  = GND
  DQS6N  = M_A_DQS_DN<6>
  DQS6P  = M_A_DQS_DP<6>
  VSS(7)  = GND
  DQ(55)  = M_A_DQ<54>
  VSS(6)  = GND
  DQ(51)  = M_A_DQ<50>
  VSS(5)  = GND
  DQ(61)  = M_A_DQ<60>
  VSS(4)  = GND
  DQ(57)  = M_A_DQ<56>
  VSS(3)  = GND
  DQS7N  = M_A_DQS_DN<7>
  DQS7P  = M_A_DQS_DP<7>
  VSS(2)  = GND
  DQ(63)  = M_A_DQ<62>
  VSS(1)  = GND
  DQ(59)  = M_A_DQ<58>
  VSS(0)  = GND
  VDDSPD  = PVPP_ABC
  SDA  = SMB_DDR_ABC_VPP_SDA
  VPP(1)  = PVPP_ABC
  VPP(0)  = PVPP_ABC
  VPP(2)  = PVPP_ABC

(kicad_pcb
	(version 20260206)
	(generator "pcbnew")
	(generator_version "10.0")
	(general
		(thickness 1.6)
		(legacy_teardrops no)
	)
	(paper "A4")
	(title_block
		(title "Wiwynn_Tioga_Pass_MB.brd")
		(comment 1 "Tioga Pass / footprint 2167 of 4770 (J4G1), pads 252-291 of 291")
	)
	(layers
		(0 "F.Cu" signal "TOP")
		(4 "In1.Cu" signal "L2GND")
		(6 "In2.Cu" signal "L3")
		(8 "In3.Cu" signal "L4GND")
		(10 "In4.Cu" signal "L5")
		(12 "In5.Cu" signal "L6GND")
		(14 "In6.Cu" signal "L7VCC")
		(16 "In7.Cu" signal "L8VCC")
		(18 "In8.Cu" signal "L9GND")
		(20 "In9.Cu" signal "L10")
		(22 "In10.Cu" signal "L11GND")
		(24 "In11.Cu" signal "L12")
		(26 "In12.Cu" signal "L13GND")
		(2 "B.Cu" signal "BOTTOM")
		(9 "F.Adhes" user "F.Adhesive")
		(11 "B.Adhes" user "B.Adhesive")
		(13 "F.Paste" user "Package Geometry/Pastemask Top")
		(15 "B.Paste" user "Package Geometry/Pastemask Bottom")
		(5 "F.SilkS" user "Ref Des/Silkscreen Top")
		(7 "B.SilkS" user "Ref Des/Silkscreen Bottom")
		(1 "F.Mask" user "Board Geometry/Soldermask Top")
		(3 "B.Mask" user "Board Geometry/Soldermask Bottom")
		(17 "Dwgs.User" user "User.Drawings")
		(19 "Cmts.User" user "User.Comments")
		(21 "Eco1.User" user "User.Eco1")
		(23 "Eco2.User" user "User.Eco2")
		(25 "Edge.Cuts" user "Board Geometry/Outline")
		(27 "Margin" user)
		(31 "F.CrtYd" user "Package Geometry/Place Bound Top")
		(29 "B.CrtYd" user "Package Geometry/Place Bound Bottom")
		(35 "F.Fab" user "Ref Des/Assembly Top")
		(33 "B.Fab" user "Ref Des/Assembly Bottom")
	)
	(footprint ""
		(layer "F.Cu")
		(at 194.700398 -15.423642 90)
		(property "Reference" "J4G1"
			(at 9.060688 37.32911 0)
			(unlocked yes)
			(layer "F.SilkS")
			(effects
				(font
					(size 0.7874 0.5842)
					(thickness 0.1524)
				)
				(justify left)
			)
		)
		(property "Value" ""
			(at 0 0 90)
			(layer "F.Fab")
			(effects
				(font
					(size 1.27 1.27)
				)
			)
		)
		(duplicate_pad_numbers_are_jumpers no)
		(pad "249" smd rect
			(at 4.59994 93.49994 90)
			(size 1.8034 0.508)
			(layers "F.Cu" "F.Mask" "F.Paste")
			(net "M_A_DQ<34>")
		)
		(pad "250" smd rect
			(at 4.59994 94.350078 90)
			(size 1.8034 0.508)
			(layers "F.Cu" "F.Mask" "F.Paste")
			(net "GND")
		)
		(pad "251" smd rect
			(at 4.59994 95.199962 90)
			(size 1.8034 0.508)
			(layers "F.Cu" "F.Mask" "F.Paste")
			(net "M_A_DQ<44>")
		)
		(pad "252" smd rect
			(at 4.59994 96.0501 90)
			(size 1.8034 0.508)
			(layers "F.Cu" "F.Mask" "F.Paste")
			(net "GND")
		)
		(pad "253" smd rect
			(at 4.59994 96.899984 90)
			(size 1.8034 0.508)
			(layers "F.Cu" "F.Mask" "F.Paste")
			(net "M_A_DQ<40>")
		)
		(pad "254" smd rect
			(at 4.59994 97.750122 90)
			(size 1.8034 0.508)
			(layers "F.Cu" "F.Mask" "F.Paste")
			(net "GND")
		)
		(pad "255" smd rect
			(at 4.59994 98.600006 90)
			(size 1.8034 0.508)
			(layers "F.Cu" "F.Mask" "F.Paste")
			(net "M_A_DQS_DN<5>")
		)
		(pad "256" smd rect
			(at 4.59994 99.44989 90)
			(size 1.8034 0.508)
			(layers "F.Cu" "F.Mask" "F.Paste")
			(net "M_A_DQS_DP<5>")
		)
		(pad "257" smd rect
			(at 4.59994 100.300028 90)
			(size 1.8034 0.508)
			(layers "F.Cu" "F.Mask" "F.Paste")
			(net "GND")
		)
		(pad "258" smd rect
			(at 4.59994 101.149912 90)
			(size 1.8034 0.508)
			(layers "F.Cu" "F.Mask" "F.Paste")
			(net "M_A_DQ<46>")
		)
		(pad "259" smd rect
			(at 4.59994 102.00005 90)
			(size 1.8034 0.508)
			(layers "F.Cu" "F.Mask" "F.Paste")
			(net "GND")
		)
		(pad "260" smd rect
			(at 4.59994 102.849934 90)
			(size 1.8034 0.508)
			(layers "F.Cu" "F.Mask" "F.Paste")
			(net "M_A_DQ<42>")
		)
		(pad "261" smd rect
			(at 4.59994 103.700072 90)
			(size 1.8034 0.508)
			(layers "F.Cu" "F.Mask" "F.Paste")
			(net "GND")
		)
		(pad "262" smd rect
			(at 4.59994 104.549956 90)
			(size 1.8034 0.508)
			(layers "F.Cu" "F.Mask" "F.Paste")
			(net "M_A_DQ<52>")
		)
		(pad "263" smd rect
			(at 4.59994 105.400094 90)
			(size 1.8034 0.508)
			(layers "F.Cu" "F.Mask" "F.Paste")
			(net "GND")
		)
		(pad "264" smd rect
			(at 4.59994 106.249978 90)
			(size 1.8034 0.508)
			(layers "F.Cu" "F.Mask" "F.Paste")
			(net "M_A_DQ<48>")
		)
		(pad "265" smd rect
			(at 4.59994 107.100116 90)
			(size 1.8034 0.508)
			(layers "F.Cu" "F.Mask" "F.Paste")
			(net "GND")
		)
		(pad "266" smd rect
			(at 4.59994 107.95 90)
			(size 1.8034 0.508)
			(layers "F.Cu" "F.Mask" "F.Paste")
			(net "M_A_DQS_DN<6>")
		)
		(pad "267" smd rect
			(at 4.59994 108.799884 90)
			(size 1.8034 0.508)
			(layers "F.Cu" "F.Mask" "F.Paste")
			(net "M_A_DQS_DP<6>")
		)
		(pad "268" smd rect
			(at 4.59994 109.650022 90)
			(size 1.8034 0.508)
			(layers "F.Cu" "F.Mask" "F.Paste")
			(net "GND")
		)
		(pad "269" smd rect
			(at 4.59994 110.499906 90)
			(size 1.8034 0.508)
			(layers "F.Cu" "F.Mask" "F.Paste")
			(net "M_A_DQ<54>")
		)
		(pad "270" smd rect
			(at 4.59994 111.350044 90)
			(size 1.8034 0.508)
			(layers "F.Cu" "F.Mask" "F.Paste")
			(net "GND")
		)
		(pad "271" smd rect
			(at 4.59994 112.199928 90)
			(size 1.8034 0.508)
			(layers "F.Cu" "F.Mask" "F.Paste")
			(net "M_A_DQ<50>")
		)
		(pad "272" smd rect
			(at 4.59994 113.050066 90)
			(size 1.8034 0.508)
			(layers "F.Cu" "F.Mask" "F.Paste")
			(net "GND")
		)
		(pad "273" smd rect
			(at 4.59994 113.89995 90)
			(size 1.8034 0.508)
			(layers "F.Cu" "F.Mask" "F.Paste")
			(net "M_A_DQ<60>")
		)
		(pad "274" smd rect
			(at 4.59994 114.750088 90)
			(size 1.8034 0.508)
			(layers "F.Cu" "F.Mask" "F.Paste")
			(net "GND")
		)
		(pad "275" smd rect
			(at 4.59994 115.599972 90)
			(size 1.8034 0.508)
			(layers "F.Cu" "F.Mask" "F.Paste")
			(net "M_A_DQ<56>")
		)
		(pad "276" smd rect
			(at 4.59994 116.45011 90)
			(size 1.8034 0.508)
			(layers "F.Cu" "F.Mask" "F.Paste")
			(net "GND")
		)
		(pad "277" smd rect
			(at 4.59994 117.299994 90)
			(size 1.8034 0.508)
			(layers "F.Cu" "F.Mask" "F.Paste")
			(net "M_A_DQS_DN<7>")
		)
		(pad "278" smd rect
			(at 4.59994 118.149878 90)
			(size 1.8034 0.508)
			(layers "F.Cu" "F.Mask" "F.Paste")
			(net "M_A_DQS_DP<7>")
		)
		(pad "279" smd rect
			(at 4.59994 119.000016 90)
			(size 1.8034 0.508)
			(layers "F.Cu" "F.Mask" "F.Paste")
			(net "GND")
		)
		(pad "280" smd rect
			(at 4.59994 119.8499 90)
			(size 1.8034 0.508)
			(layers "F.Cu" "F.Mask" "F.Paste")
			(net "M_A_DQ<62>")
		)
		(pad "281" smd rect
			(at 4.59994 120.700038 90)
			(size 1.8034 0.508)
			(layers "F.Cu" "F.Mask" "F.Paste")
			(net "GND")
		)
		(pad "282" smd rect
			(at 4.59994 121.549922 90)
			(size 1.8034 0.508)
			(layers "F.Cu" "F.Mask" "F.Paste")
			(net "M_A_DQ<58>")
		)
		(pad "283" smd rect
			(at 4.59994 122.40006 90)
			(size 1.8034 0.508)
			(layers "F.Cu" "F.Mask" "F.Paste")
			(net "GND")
		)
		(pad "284" smd rect
			(at 4.59994 123.249944 90)
			(size 1.8034 0.508)
			(layers "F.Cu" "F.Mask" "F.Paste")
			(net "PVPP_ABC")
		)
		(pad "285" smd rect
			(at 4.59994 124.100082 90)
			(size 1.8034 0.508)
			(layers "F.Cu" "F.Mask" "F.Paste")
			(net "SMB_DDR_ABC_VPP_SDA")
		)
		(pad "286" smd rect
			(at 4.59994 124.949966 90)
			(size 1.8034 0.508)
			(layers "F.Cu" "F.Mask" "F.Paste")
			(net "PVPP_ABC")
		)
		(pad "287" smd rect
			(at 4.59994 125.800104 90)
			(size 1.8034 0.508)
			(layers "F.Cu" "F.Mask" "F.Paste")
			(net "PVPP_ABC")
		)
		(pad "288" smd rect
			(at 4.59994 126.649988 90)
			(size 1.8034 0.508)
			(layers "F.Cu" "F.Mask" "F.Paste")
			(net "PVPP_ABC")
		)
	)
)
